(kicad_pcb
	(version 20260206)
	(generator "pcbnew")
	(generator_version "10.0")
	(general
		(thickness 1.6)
		(legacy_teardrops no)
	)
	(paper "A4")
	(title_block
		(title "03242023_DA0F0TMBIJ0_F0T_Motherboard_J_brd_V01_OCP.brd")
		(comment 1 "Grand Teton / footprints 4008-4011 of 6105")
	)
	(layers
		(0 "F.Cu" signal "TOP")
		(4 "In1.Cu" signal "GND")
		(6 "In2.Cu" signal "IN1")
		(8 "In3.Cu" signal "GND1")
		(10 "In4.Cu" signal "IN2")
		(12 "In5.Cu" signal "GND2")
		(14 "In6.Cu" signal "IN3")
		(16 "In7.Cu" signal "GND3")
		(18 "In8.Cu" signal "VCC")
		(20 "In9.Cu" signal "VCC1")
		(22 "In10.Cu" signal "GND4")
		(24 "In11.Cu" signal "IN4")
		(26 "In12.Cu" signal "GND5")
		(28 "In13.Cu" signal "IN5")
		(30 "In14.Cu" signal "GND6")
		(32 "In15.Cu" signal "IN6")
		(34 "In16.Cu" signal "GND7")
		(2 "B.Cu" signal "BOTTOM")
		(9 "F.Adhes" user "F.Adhesive")
		(11 "B.Adhes" user "B.Adhesive")
		(13 "F.Paste" user "Package Geometry/Pastemask Top")
		(15 "B.Paste" user "Package Geometry/Pastemask Bottom")
		(5 "F.SilkS" user "Ref Des/Silkscreen Top")
		(7 "B.SilkS" user "Ref Des/Silkscreen Bottom")
		(1 "F.Mask" user "Board Geometry/Soldermask Top")
		(3 "B.Mask" user "Board Geometry/Soldermask Bottom")
		(17 "Dwgs.User" user "User.Drawings")
		(19 "Cmts.User" user "User.Comments")
		(21 "Eco1.User" user "User.Eco1")
		(23 "Eco2.User" user "User.Eco2")
		(25 "Edge.Cuts" user "Board Geometry/Outline")
		(27 "Margin" user)
		(31 "F.CrtYd" user "Package Geometry/Place Bound Top")
		(29 "B.CrtYd" user "Package Geometry/Place Bound Bottom")
		(35 "F.Fab" user "Ref Des/Assembly Top")
		(33 "B.Fab" user "Ref Des/Assembly Bottom")
	)
	(footprint ""
		(layer "F.Cu")
		(at 16.645382 -105.56621 90)
		(property "Reference" "R2791"
			(at 0 0 90)
			(layer "F.SilkS")
			(hide yes)
			(effects
				(font
					(size 1.27 1.27)
				)
			)
		)
		(property "Value" ""
			(at 0 0 90)
			(layer "F.Fab")
			(effects
				(font
					(size 1.27 1.27)
				)
			)
		)
		(duplicate_pad_numbers_are_jumpers no)
		(fp_line
			(start -0.01651 -0.4064)
			(end 0.7874 -0.4064)
			(stroke
				(width 0.1524)
				(type default)
			)
			(layer "F.SilkS")
		)
		(fp_line
			(start 0.7874 0.4064)
			(end -0.02921 0.4064)
			(stroke
				(width 0.1524)
				(type default)
			)
			(layer "F.SilkS")
		)
		(fp_line
			(start -0.7874 0.4064)
			(end -0.7874 -0.4064)
			(stroke
				(width 0.1524)
				(type default)
			)
			(layer "F.SilkS")
		)
		(fp_line
			(start -0.12065 -0.305054)
			(end -0.12065 -0.2794)
			(stroke
				(width 0.1)
				(type default)
			)
			(layer "F.Fab")
		)
		(fp_line
			(start -0.67945 -0.305054)
			(end -0.12065 -0.305054)
			(stroke
				(width 0.1)
				(type default)
			)
			(layer "F.Fab")
		)
		(fp_line
			(start 0.67945 -0.3048)
			(end 0.67945 0.3048)
			(stroke
				(width 0.1)
				(type default)
			)
			(layer "F.Fab")
		)
		(fp_line
			(start 0.12065 -0.3048)
			(end 0.67945 -0.3048)
			(stroke
				(width 0.1)
				(type default)
			)
			(layer "F.Fab")
		)
		(fp_line
			(start 0.12065 -0.2794)
			(end 0.12065 -0.3048)
			(stroke
				(width 0.1)
				(type default)
			)
			(layer "F.Fab")
		)
		(fp_line
			(start -0.12065 -0.2794)
			(end 0.12065 -0.2794)
			(stroke
				(width 0.1)
				(type default)
			)
			(layer "F.Fab")
		)
		(fp_line
			(start 0.120396 0.2794)
			(end -0.12065 0.2794)
			(stroke
				(width 0.1)
				(type default)
			)
			(layer "F.Fab")
		)
		(fp_line
			(start -0.12065 0.2794)
			(end -0.12065 0.3048)
			(stroke
				(width 0.1)
				(type default)
			)
			(layer "F.Fab")
		)
		(fp_line
			(start 0.67945 0.3048)
			(end 0.120396 0.3048)
			(stroke
				(width 0.1)
				(type default)
			)
			(layer "F.Fab")
		)
		(fp_line
			(start 0.120396 0.3048)
			(end 0.120396 0.2794)
			(stroke
				(width 0.1)
				(type default)
			)
			(layer "F.Fab")
		)
		(fp_line
			(start -0.12065 0.3048)
			(end -0.67945 0.3048)
			(stroke
				(width 0.1)
				(type default)
			)
			(layer "F.Fab")
		)
		(fp_line
			(start -0.67945 0.3048)
			(end -0.67945 -0.305054)
			(stroke
				(width 0.1)
				(type default)
			)
			(layer "F.Fab")
		)
		(pad "1" smd rect
			(at -0.40005 0 270)
			(size 0.4572 0.508)
			(layers "F.Cu" "F.Mask" "F.Paste")
			(net "USB2_HOST_BMC_B_DN")
		)
		(pad "2" smd rect
			(at 0.40005 0 270)
			(size 0.4572 0.508)
			(layers "F.Cu" "F.Mask" "F.Paste")
			(net "USB2_HOST_BMC_B_BUF_DN")
		)
	)
	(footprint ""
		(layer "F.Cu")
		(at 118.804944 -77.748892 180)
		(property "Reference" "U97"
			(at 0.831088 2.72542 0)
			(unlocked yes)
			(layer "F.SilkS")
			(effects
				(font
					(size 0.7874 0.5842)
					(thickness 0.1524)
				)
				(justify left)
			)
		)
		(property "Value" ""
			(at 0 0 180)
			(layer "F.Fab")
			(effects
				(font
					(size 1.27 1.27)
				)
			)
		)
		(duplicate_pad_numbers_are_jumpers no)
		(fp_line
			(start 0.824992 1.050036)
			(end 0.254 1.050036)
			(stroke
				(width 0.1524)
				(type default)
			)
			(layer "F.SilkS")
		)
		(fp_line
			(start 0.824992 1.00584)
			(end 0.824992 1.050036)
			(stroke
				(width 0.1524)
				(type default)
			)
			(layer "F.SilkS")
		)
		(fp_line
			(start 0.824992 -1.050036)
			(end 0.824992 -1.00584)
			(stroke
				(width 0.1524)
				(type default)
			)
			(layer "F.SilkS")
		)
		(fp_line
			(start 0.254 -1.050036)
			(end 0.824992 -1.050036)
			(stroke
				(width 0.1524)
				(type default)
			)
			(layer "F.SilkS")
		)
		(fp_line
			(start -0.254 1.050036)
			(end -0.824992 1.050036)
			(stroke
				(width 0.1524)
				(type default)
			)
			(layer "F.SilkS")
		)
		(fp_line
			(start -0.824992 1.050036)
			(end -0.824992 1.00584)
			(stroke
				(width 0.1524)
				(type default)
			)
			(layer "F.SilkS")
		)
		(fp_line
			(start -0.824992 -1.01854)
			(end -0.824992 -1.050036)
			(stroke
				(width 0.1524)
				(type default)
			)
			(layer "F.SilkS")
		)
		(fp_line
			(start -0.824992 -1.050036)
			(end -0.254 -1.050036)
			(stroke
				(width 0.1524)
				(type default)
			)
			(layer "F.SilkS")
		)
		(fp_poly
			(pts
				(xy -2.027428 -0.399034) (xy -2.027428 -1.10109) (xy -1.325372 -0.750062)
			)
			(stroke
				(width 0)
				(type default)
			)
			(fill yes)
			(layer "F.SilkS")
		)
		(fp_line
			(start 0.824992 1.050036)
			(end -0.824992 1.050036)
			(stroke
				(width 0.1)
				(type default)
			)
			(layer "F.Fab")
		)
		(fp_line
			(start 0.824992 -1.050036)
			(end 0.824992 1.050036)
			(stroke
				(width 0.1)
				(type default)
			)
			(layer "F.Fab")
		)
		(fp_line
			(start -0.824992 1.050036)
			(end -0.824992 -1.050036)
			(stroke
				(width 0.1)
				(type default)
			)
			(layer "F.Fab")
		)
		(fp_line
			(start -0.824992 -1.050036)
			(end 0.824992 -1.050036)
			(stroke
				(width 0.1)
				(type default)
			)
			(layer "F.Fab")
		)
		(fp_poly
			(pts
				(xy -1.325372 -0.750062) (xy -2.027428 -0.399034) (xy -2.027428 -1.10109)
			)
			(stroke
				(width 0)
				(type default)
			)
			(fill yes)
			(layer "F.Fab")
		)
		(pad "1" smd rect
			(at -0.741172 -0.750062 270)
			(size 0.2794 0.8128)
			(layers "F.Cu" "F.Mask" "F.Paste")
			(net "JTAG_BMC_PLD_TMS")
		)
		(pad "2" smd rect
			(at -0.741172 -0.249936 270)
			(size 0.254 0.8128)
			(layers "F.Cu" "F.Mask" "F.Paste")
			(net "JTAG_BMC_DBP_TMS")
		)
		(pad "3" smd rect
			(at -0.741172 0.249936 270)
			(size 0.254 0.8128)
			(layers "F.Cu" "F.Mask" "F.Paste")
			(net "JTAG_BMC_PLD_TCK")
		)
		(pad "4" smd rect
			(at -0.741172 0.750062 270)
			(size 0.254 0.8128)
			(layers "F.Cu" "F.Mask" "F.Paste")
			(net "JTAG_BMC_DBP_TCK")
		)
		(pad "5" smd rect
			(at 0 0.94996 180)
			(size 0.254 0.8128)
			(layers "F.Cu" "F.Mask" "F.Paste")
			(net "GND")
		)
		(pad "6" smd rect
			(at 0.741172 0.750062 270)
			(size 0.254 0.8128)
			(layers "F.Cu" "F.Mask" "F.Paste")
			(net "JTAG_BMC_SW_TCK")
		)
		(pad "7" smd rect
			(at 0.741172 0.249936 270)
			(size 0.254 0.8128)
			(layers "F.Cu" "F.Mask" "F.Paste")
			(net "FM_JTAG_BMC_MUX_SEL")
		)
		(pad "8" smd rect
			(at 0.741172 -0.249936 270)
			(size 0.254 0.8128)
			(layers "F.Cu" "F.Mask" "F.Paste")
			(net "FM_JTAG_BMC_MUX_SEL")
		)
		(pad "9" smd rect
			(at 0.741172 -0.750062 270)
			(size 0.254 0.8128)
			(layers "F.Cu" "F.Mask" "F.Paste")
			(net "JTAG_BMC_SW_TMS")
		)
		(pad "10" smd rect
			(at 0 -0.94996 180)
			(size 0.254 0.8128)
			(layers "F.Cu" "F.Mask" "F.Paste")
			(net "P3V3_AUX")
		)
		(zone
			(layer "F.Cu")
			(hatch none 0.5)
			(connect_pads
				(clearance 0)
			)
			(min_thickness 0.25)
			(keepout
				(tracks not_allowed)
				(vias allowed)
				(pads allowed)
				(copperpour not_allowed)
				(footprints allowed)
			)
			(placement
				(enabled no)
				(sheetname "")
			)
			(fill
				(thermal_gap 0.5)
				(thermal_bridge_width 0.5)
				(island_removal_mode 0)
			)
			(polygon
				(pts
					(xy 119.630444 -76.809092) (xy 119.630444 -76.694792) (xy 119.084344 -76.694792) (xy 119.084344 -76.809092)
				)
			)
		)
	)
	(footprint ""
		(layer "F.Cu")
		(at 113.20653 -15.879064)
		(property "Reference" "U273"
			(at -2.57937 -5.227574 0)
			(unlocked yes)
			(layer "F.SilkS")
			(effects
				(font
					(size 0.7874 0.5842)
					(thickness 0.1524)
				)
				(justify left)
			)
		)
		(property "Value" ""
			(at 0 0 0)
			(layer "F.Fab")
			(effects
				(font
					(size 1.27 1.27)
				)
			)
		)
		(duplicate_pad_numbers_are_jumpers no)
		(fp_line
			(start -3.447796 -2.500122)
			(end -3.447796 2.500122)
			(stroke
				(width 0.1524)
				(type default)
			)
			(layer "F.SilkS")
		)
		(fp_line
			(start -3.447796 2.500122)
			(end 3.447796 2.500122)
			(stroke
				(width 0.1524)
				(type default)
			)
			(layer "F.SilkS")
		)
		(fp_line
			(start -1.484122 -2.500122)
			(end -3.447796 -2.500122)
			(stroke
				(width 0.1524)
				(type default)
			)
			(layer "F.SilkS")
		)
		(fp_line
			(start 0 -1.016)
			(end -1.484122 -2.500122)
			(stroke
				(width 0.1524)
				(type default)
			)
			(layer "F.SilkS")
		)
		(fp_line
			(start 1.484122 -2.500122)
			(end 0 -1.016)
			(stroke
				(width 0.1524)
				(type default)
			)
			(layer "F.SilkS")
		)
		(fp_line
			(start 3.447796 -2.500122)
			(end 1.484122 -2.500122)
			(stroke
				(width 0.1524)
				(type default)
			)
			(layer "F.SilkS")
		)
		(fp_line
			(start 3.447796 2.500122)
			(end 3.447796 -2.500122)
			(stroke
				(width 0.1524)
				(type default)
			)
			(layer "F.SilkS")
		)
		(fp_poly
			(pts
				(xy -2.309114 -3.855974) (xy -2.817114 -2.839974) (xy -3.325114 -3.855974)
			)
			(stroke
				(width 0)
				(type default)
			)
			(fill yes)
			(layer "F.SilkS")
		)
		(fp_line
			(start -1.999996 -2.500122)
			(end -1.999996 2.500122)
			(stroke
				(width 0.1)
				(type default)
			)
			(layer "F.Fab")
		)
		(fp_line
			(start -1.999996 2.500122)
			(end 1.999996 2.500122)
			(stroke
				(width 0.1)
				(type default)
			)
			(layer "F.Fab")
		)
		(fp_line
			(start 1.999996 -2.500122)
			(end -1.999996 -2.500122)
			(stroke
				(width 0.1)
				(type default)
			)
			(layer "F.Fab")
		)
		(fp_line
			(start 1.999996 2.500122)
			(end 1.999996 -2.500122)
			(stroke
				(width 0.1)
				(type default)
			)
			(layer "F.Fab")
		)
		(fp_poly
			(pts
				(xy -4.5974 -2.413) (xy -4.5974 -1.397) (xy -3.5814 -1.905)
			)
			(stroke
				(width 0)
				(type default)
			)
			(fill yes)
			(layer "F.Fab")
		)
		(pad "1" smd rect
			(at -2.649982 -1.905 270)
			(size 0.6096 1.3208)
			(layers "F.Cu" "F.Mask" "F.Paste")
			(net "SMB_LM75_3_3V3AUX_SDA_R1")
		)
		(pad "2" smd rect
			(at -2.649982 -0.635 270)
			(size 0.6096 1.3208)
			(layers "F.Cu" "F.Mask" "F.Paste")
			(net "SMB_LM75_3_3V3AUX_SCL_R1")
		)
		(pad "3" smd rect
			(at -2.649982 0.635 270)
			(size 0.6096 1.3208)
			(layers "F.Cu" "F.Mask" "F.Paste")
			(net "FM_LM75_3_ALERT_N")
		)
		(pad "4" smd rect
			(at -2.649982 1.905 270)
			(size 0.6096 1.3208)
			(layers "F.Cu" "F.Mask" "F.Paste")
			(net "GND")
		)
		(pad "5" smd rect
			(at 2.649982 1.905 270)
			(size 0.6096 1.3208)
			(layers "F.Cu" "F.Mask" "F.Paste")
			(net "U273_3_ADD2")
		)
		(pad "6" smd rect
			(at 2.649982 0.635 270)
			(size 0.6096 1.3208)
			(layers "F.Cu" "F.Mask" "F.Paste")
			(net "U273_3_ADD1")
		)
		(pad "7" smd rect
			(at 2.649982 -0.635 270)
			(size 0.6096 1.3208)
			(layers "F.Cu" "F.Mask" "F.Paste")
			(net "U273_3_ADD0")
		)
		(pad "8" smd rect
			(at 2.649982 -1.905 270)
			(size 0.6096 1.3208)
			(layers "F.Cu" "F.Mask" "F.Paste")
			(net "P3V3_AUX")
		)
	)
	(footprint ""
		(layer "F.Cu")
		(at 31.29788 -429.859948)
		(property "Reference" "R2932"
			(at 0 0 0)
			(layer "F.SilkS")
			(hide yes)
			(effects
				(font
					(size 1.27 1.27)
				)
			)
		)
		(property "Value" ""
			(at 0 0 0)
			(layer "F.Fab")
			(effects
				(font
					(size 1.27 1.27)
				)
			)
		)
		(duplicate_pad_numbers_are_jumpers no)
		(fp_line
			(start -0.7874 -0.4064)
			(end 0.7874 -0.4064)
			(stroke
				(width 0.1524)
				(type default)
			)
			(layer "F.SilkS")
		)
		(fp_line
			(start -0.7874 0.4064)
			(end -0.7874 -0.4064)
			(stroke
				(width 0.1524)
				(type default)
			)
			(layer "F.SilkS")
		)
		(fp_line
			(start 0.7874 -0.4064)
			(end 0.7874 0.4064)
			(stroke
				(width 0.1524)
				(type default)
			)
			(layer "F.SilkS")
		)
		(fp_line
			(start 0.7874 0.4064)
			(end -0.7874 0.4064)
			(stroke
				(width 0.1524)
				(type default)
			)
			(layer "F.SilkS")
		)
		(fp_line
			(start -0.67945 -0.305054)
			(end -0.12065 -0.305054)
			(stroke
				(width 0.1)
				(type default)
			)
			(layer "F.Fab")
		)
		(fp_line
			(start -0.67945 0.3048)
			(end -0.67945 -0.305054)
			(stroke
				(width 0.1)
				(type default)
			)
			(layer "F.Fab")
		)
		(fp_line
			(start -0.12065 -0.305054)
			(end -0.12065 -0.2794)
			(stroke
				(width 0.1)
				(type default)
			)
			(layer "F.Fab")
		)
		(fp_line
			(start -0.12065 -0.2794)
			(end 0.12065 -0.2794)
			(stroke
				(width 0.1)
				(type default)
			)
			(layer "F.Fab")
		)
		(fp_line
			(start -0.12065 0.2794)
			(end -0.12065 0.3048)
			(stroke
				(width 0.1)
				(type default)
			)
			(layer "F.Fab")
		)
		(fp_line
			(start -0.12065 0.3048)
			(end -0.67945 0.3048)
			(stroke
				(width 0.1)
				(type default)
			)
			(layer "F.Fab")
		)
		(fp_line
			(start 0.120396 0.2794)
			(end -0.12065 0.2794)
			(stroke
				(width 0.1)
				(type default)
			)
			(layer "F.Fab")
		)
		(fp_line
			(start 0.120396 0.3048)
			(end 0.120396 0.2794)
			(stroke
				(width 0.1)
				(type default)
			)
			(layer "F.Fab")
		)
		(fp_line
			(start 0.12065 -0.3048)
			(end 0.67945 -0.3048)
			(stroke
				(width 0.1)
				(type default)
			)
			(layer "F.Fab")
		)
		(fp_line
			(start 0.12065 -0.2794)
			(end 0.12065 -0.3048)
			(stroke
				(width 0.1)
				(type default)
			)
			(layer "F.Fab")
		)
		(fp_line
			(start 0.67945 -0.3048)
			(end 0.67945 0.3048)
			(stroke
				(width 0.1)
				(type default)
			)
			(layer "F.Fab")
		)
		(fp_line
			(start 0.67945 0.3048)
			(end 0.120396 0.3048)
			(stroke
				(width 0.1)
				(type default)
			)
			(layer "F.Fab")
		)
		(pad "1" smd circle
			(at -0.40005 0)
			(size 0 0)
			(layers "F.Cu" "F.Mask" "F.Paste")
			(net "FM_SWB_PWR_EN_R1_BUF")
		)
		(pad "2" smd circle
			(at 0.40005 0)
			(size 0 0)
			(layers "F.Cu" "F.Mask" "F.Paste")
			(net "GND")
		)
	)
)
